(kicad_pcb
	(version 20260206)
	(generator "pcbnew")
	(generator_version "10.0")
	(general
		(thickness 1.6)
		(legacy_teardrops no)
	)
	(paper "A4")
	(title_block
		(title "Bryce Canyon_R.DPB_16317-1_OCP.brd")
		(comment 1 "Bryce Canyon / footprints 293-295 of 2099")
	)
	(layers
		(0 "F.Cu" signal "TOP")
		(4 "In1.Cu" signal "L2GND")
		(6 "In2.Cu" signal "L3")
		(8 "In3.Cu" signal "L4VCC")
		(10 "In4.Cu" signal "L5VCC")
		(12 "In5.Cu" signal "L6")
		(14 "In6.Cu" signal "L7GND")
		(2 "B.Cu" signal "BOTTOM")
		(9 "F.Adhes" user "F.Adhesive")
		(11 "B.Adhes" user "B.Adhesive")
		(13 "F.Paste" user "Package Geometry/Pastemask Top")
		(15 "B.Paste" user "Package Geometry/Pastemask Bottom")
		(5 "F.SilkS" user "Ref Des/Silkscreen Top")
		(7 "B.SilkS" user "Ref Des/Silkscreen Bottom")
		(1 "F.Mask" user "Board Geometry/Soldermask Top")
		(3 "B.Mask" user "Board Geometry/Soldermask Bottom")
		(17 "Dwgs.User" user "User.Drawings")
		(19 "Cmts.User" user "User.Comments")
		(21 "Eco1.User" user "User.Eco1")
		(23 "Eco2.User" user "User.Eco2")
		(25 "Edge.Cuts" user "Board Geometry/Outline")
		(27 "Margin" user)
		(31 "F.CrtYd" user "Package Geometry/Place Bound Top")
		(29 "B.CrtYd" user "Package Geometry/Place Bound Bottom")
		(35 "F.Fab" user "Ref Des/Assembly Top")
		(33 "B.Fab" user "Ref Des/Assembly Bottom")
	)
	(footprint ""
		(layer "F.Cu")
		(at 325.550022 -258.910074 -90)
		(property "Reference" "HDDSAS6"
			(at 0 0 270)
			(layer "F.SilkS")
			(hide yes)
			(effects
				(font
					(size 1.27 1.27)
				)
			)
		)
		(property "Value" "SKT-SAS15P-14P-45-GP"
			(at -20.7645 -8.9789 270)
			(unlocked yes)
			(layer "F.Fab")
			(hide yes)
			(effects
				(font
					(size 1.016 1.016)
					(thickness 0.1524)
				)
			)
		)
		(property "Device Type" "10120818-001C-TRLF"
			(at -20.7645 -10.5029 270)
			(unlocked yes)
			(layer "F.Fab")
			(hide yes)
			(effects
				(font
					(size 1.016 1.016)
					(thickness 0.1524)
				)
			)
		)
		(duplicate_pad_numbers_are_jumpers no)
		(fp_line
			(start 1.651 4.2926)
			(end 1.651 3.0099)
			(stroke
				(width 0.1524)
				(type default)
			)
			(layer "F.SilkS")
		)
		(fp_line
			(start 8.509 4.2926)
			(end 1.651 4.2926)
			(stroke
				(width 0.1524)
				(type default)
			)
			(layer "F.SilkS")
		)
		(fp_line
			(start -23.4188 3.0099)
			(end -23.4188 -3.2512)
			(stroke
				(width 0.1524)
				(type default)
			)
			(layer "F.SilkS")
		)
		(fp_line
			(start 1.651 3.0099)
			(end -23.4188 3.0099)
			(stroke
				(width 0.1524)
				(type default)
			)
			(layer "F.SilkS")
		)
		(fp_line
			(start 8.509 3.0099)
			(end 8.509 4.2926)
			(stroke
				(width 0.1524)
				(type default)
			)
			(layer "F.SilkS")
		)
		(fp_line
			(start 23.4188 3.0099)
			(end 8.509 3.0099)
			(stroke
				(width 0.1524)
				(type default)
			)
			(layer "F.SilkS")
		)
		(fp_line
			(start -23.4188 -3.2512)
			(end 23.4188 -3.2512)
			(stroke
				(width 0.1524)
				(type default)
			)
			(layer "F.SilkS")
		)
		(fp_line
			(start 23.4188 -3.2512)
			(end 23.4188 3.0099)
			(stroke
				(width 0.1524)
				(type default)
			)
			(layer "F.SilkS")
		)
		(fp_line
			(start 15.5067 -3.3401)
			(end 16.2687 -3.3401)
			(stroke
				(width 0.3302)
				(type default)
			)
			(layer "F.SilkS")
		)
		(fp_poly
			(pts
				(xy 15.868904 -3.230372) (xy 16.503904 -3.865372) (xy 15.233904 -3.865372)
			)
			(stroke
				(width 0)
				(type default)
			)
			(fill yes)
			(layer "F.SilkS")
		)
		(fp_poly
			(pts
				(xy -22.8727 -2.7559) (xy 22.8727 -2.7559) (xy 22.8727 2.7559) (xy 8.255 2.7559) (xy 8.255 3.5179)
				(xy 1.905 3.5179) (xy 1.905 2.7559) (xy -22.8727 2.7559)
			)
			(stroke
				(width 0)
				(type default)
			)
			(fill no)
			(layer "F.CrtYd")
		)
		(fp_poly
			(pts
				(xy 1.397 4.5466) (xy 1.397 3.2639) (xy -23.6728 3.2639) (xy -23.6728 -3.5052) (xy 23.6728 -3.5052)
				(xy 23.6728 -0.00635) (xy 22.8727 -0.00635) (xy 22.8727 -2.7559) (xy -22.8727 -2.7559) (xy -22.8727 2.7559)
				(xy 1.905 2.7559) (xy 1.905 3.5179) (xy 8.255 3.5179) (xy 8.255 2.7559) (xy 22.8727 2.7559) (xy 22.8727 0.00635)
				(xy 23.6728 0.00635) (xy 23.6728 3.2639) (xy 8.763 3.2639) (xy 8.763 4.5466)
			)
			(stroke
				(width 0)
				(type default)
			)
			(fill no)
			(layer "F.CrtYd")
		)
		(fp_poly
			(pts
				(xy 1.397 4.5466) (xy 1.397 3.2639) (xy -23.6728 3.2639) (xy -23.6728 -3.5052) (xy 23.6728 -3.5052)
				(xy 23.6728 3.2639) (xy 8.763 3.2639) (xy 8.763 4.5466)
			)
			(stroke
				(width 0)
				(type default)
			)
			(fill no)
			(layer "F.Fab")
		)
		(pad "" np_thru_hole circle
			(at -18.874994 0 270)
			(size 0.254 0.254)
			(drill 1.3462)
			(layers "*.Cu" "*.Mask")
			(clearance 0.9017)
			(thermal_gap 0.9017)
		)
		(pad "" np_thru_hole circle
			(at 18.874994 0 270)
			(size 0.254 0.254)
			(drill 0.9398)
			(layers "*.Cu" "*.Mask")
			(clearance 0.6985)
			(thermal_gap 0.6985)
		)
		(pad "G1" smd rect
			(at 21.874988 0 270)
			(size 2.5908 2.5908)
			(layers "F.Cu" "F.Mask" "F.Paste")
			(net "GND")
		)
		(pad "G2" smd rect
			(at -21.874988 0 270)
			(size 2.5908 2.5908)
			(layers "F.Cu" "F.Mask" "F.Paste")
			(net "GND")
		)
		(pad "P1" smd rect
			(at 1.905 -1.82499 270)
			(size 0.6096 2.3622)
			(layers "F.Cu" "F.Mask" "F.Paste")
			(net "Net_1599")
		)
		(pad "P2" smd rect
			(at 0.635 -1.82499 270)
			(size 0.6096 2.3622)
			(layers "F.Cu" "F.Mask" "F.Paste")
			(net "Net_1600")
		)
		(pad "P3" smd rect
			(at -0.635 -1.82499 270)
			(size 0.6096 2.3622)
			(layers "F.Cu" "F.Mask" "F.Paste")
			(net "Net_1601")
		)
		(pad "P4" smd rect
			(at -1.905 -1.82499 270)
			(size 0.6096 2.3622)
			(layers "F.Cu" "F.Mask" "F.Paste")
			(net "GND")
		)
		(pad "P5" smd rect
			(at -3.175 -1.82499 270)
			(size 0.6096 2.3622)
			(layers "F.Cu" "F.Mask" "F.Paste")
			(net "HDD_PRSNT_6")
		)
		(pad "P6" smd rect
			(at -4.445 -1.82499 270)
			(size 0.6096 2.3622)
			(layers "F.Cu" "F.Mask" "F.Paste")
			(net "GND")
		)
		(pad "P7" smd rect
			(at -5.715 -1.82499 270)
			(size 0.6096 2.3622)
			(layers "F.Cu" "F.Mask" "F.Paste")
			(net "5V_PRE_6")
		)
		(pad "P8" smd rect
			(at -6.985 -1.82499 270)
			(size 0.6096 2.3622)
			(layers "F.Cu" "F.Mask" "F.Paste")
			(net "P5V_HDD6")
		)
		(pad "P9" smd rect
			(at -8.255 -1.82499 270)
			(size 0.6096 2.3622)
			(layers "F.Cu" "F.Mask" "F.Paste")
			(net "P5V_HDD6")
		)
		(pad "P10" smd rect
			(at -9.525 -1.82499 270)
			(size 0.6096 2.3622)
			(layers "F.Cu" "F.Mask" "F.Paste")
			(net "GND")
		)
		(pad "P11" smd rect
			(at -10.795 -1.82499 270)
			(size 0.6096 2.3622)
			(layers "F.Cu" "F.Mask" "F.Paste")
			(net "ACT_HDD_6")
		)
		(pad "P12" smd rect
			(at -12.065 -1.82499 270)
			(size 0.6096 2.3622)
			(layers "F.Cu" "F.Mask" "F.Paste")
			(net "GND")
		)
		(pad "P13" smd rect
			(at -13.335 -1.82499 270)
			(size 0.6096 2.3622)
			(layers "F.Cu" "F.Mask" "F.Paste")
			(net "12V_PRE_6")
		)
		(pad "P14" smd rect
			(at -14.605 -1.82499 270)
			(size 0.6096 2.3622)
			(layers "F.Cu" "F.Mask" "F.Paste")
			(net "P12V_HDD6")
		)
		(pad "P15" smd rect
			(at -15.875 -1.82499 270)
			(size 0.6096 2.3622)
			(layers "F.Cu" "F.Mask" "F.Paste")
			(net "P12V_HDD6")
		)
		(pad "S1" smd rect
			(at 15.875 -1.82499 270)
			(size 0.6096 2.3622)
			(layers "F.Cu" "F.Mask" "F.Paste")
			(net "GND")
		)
		(pad "S2" smd rect
			(at 14.605 -1.82499 270)
			(size 0.6096 2.3622)
			(layers "F.Cu" "F.Mask" "F.Paste")
			(net "SAS_HDD_RX_P6")
		)
		(pad "S3" smd rect
			(at 13.335 -1.82499 270)
			(size 0.6096 2.3622)
			(layers "F.Cu" "F.Mask" "F.Paste")
			(net "SAS_HDD_RX_N6")
		)
		(pad "S4" smd rect
			(at 12.065 -1.82499 270)
			(size 0.6096 2.3622)
			(layers "F.Cu" "F.Mask" "F.Paste")
			(net "GND")
		)
		(pad "S5" smd rect
			(at 10.795 -1.82499 270)
			(size 0.6096 2.3622)
			(layers "F.Cu" "F.Mask" "F.Paste")
			(net "PHY_DRV_B_TO_SCC_B_6_DN")
		)
		(pad "S6" smd rect
			(at 9.525 -1.82499 270)
			(size 0.6096 2.3622)
			(layers "F.Cu" "F.Mask" "F.Paste")
			(net "PHY_DRV_B_TO_SCC_B_6_DP")
		)
		(pad "S7" smd rect
			(at 8.255 -1.82499 270)
			(size 0.6096 2.3622)
			(layers "F.Cu" "F.Mask" "F.Paste")
			(net "GND")
		)
		(pad "S8" smd rect
			(at 7.480046 2.845054 270)
			(size 0.508 2.3622)
			(layers "F.Cu" "F.Mask" "F.Paste")
			(net "GND")
		)
		(pad "S9" smd rect
			(at 6.679946 2.845054 270)
			(size 0.508 2.3622)
			(layers "F.Cu" "F.Mask" "F.Paste")
			(net "Net_464")
		)
		(pad "S10" smd rect
			(at 5.8801 2.845054 270)
			(size 0.508 2.3622)
			(layers "F.Cu" "F.Mask" "F.Paste")
			(net "Net_356")
		)
		(pad "S11" smd rect
			(at 5.08 2.845054 270)
			(size 0.508 2.3622)
			(layers "F.Cu" "F.Mask" "F.Paste")
			(net "GND")
		)
		(pad "S12" smd rect
			(at 4.2799 2.845054 270)
			(size 0.508 2.3622)
			(layers "F.Cu" "F.Mask" "F.Paste")
			(net "Net_392")
		)
		(pad "S13" smd rect
			(at 3.480054 2.845054 270)
			(size 0.508 2.3622)
			(layers "F.Cu" "F.Mask" "F.Paste")
			(net "Net_428")
		)
		(pad "S14" smd rect
			(at 2.679954 2.845054 270)
			(size 0.508 2.3622)
			(layers "F.Cu" "F.Mask" "F.Paste")
			(net "GND")
		)
		(zone
			(layer "F.Cu")
			(hatch none 0.5)
			(connect_pads
				(clearance 0)
			)
			(min_thickness 0.25)
			(keepout
				(tracks allowed)
				(vias not_allowed)
				(pads allowed)
				(copperpour not_allowed)
				(footprints allowed)
			)
			(placement
				(enabled no)
				(sheetname "")
			)
			(fill
				(thermal_gap 0.5)
				(thermal_bridge_width 0.5)
				(island_removal_mode 0)
			)
			(polygon
				(pts
					(xy 329.207622 -275.648674) (xy 322.133722 -275.648674) (xy 322.133722 -282.582874) (xy 323.238622 -282.582874)
					(xy 323.238622 -278.468074) (xy 327.861422 -278.468074) (xy 327.861422 -282.582874) (xy 329.207622 -282.582874)
				)
			)
		)
		(zone
			(layer "F.Cu")
			(hatch none 0.5)
			(connect_pads
				(clearance 0)
			)
			(min_thickness 0.25)
			(keepout
				(tracks not_allowed)
				(vias allowed)
				(pads allowed)
				(copperpour not_allowed)
				(footprints allowed)
			)
			(placement
				(enabled no)
				(sheetname "")
			)
			(fill
				(thermal_gap 0.5)
				(thermal_bridge_width 0.5)
				(island_removal_mode 0)
			)
			(polygon
				(pts
					(xy 329.207622 -275.648674) (xy 322.133722 -275.648674) (xy 322.133722 -282.582874) (xy 323.238622 -282.582874)
					(xy 323.238622 -278.468074) (xy 327.861422 -278.468074) (xy 327.861422 -282.582874) (xy 329.207622 -282.582874)
				)
			)
		)
		(zone
			(layer "F.Cu")
			(hatch none 0.5)
			(connect_pads
				(clearance 0)
			)
			(min_thickness 0.25)
			(keepout
				(tracks not_allowed)
				(vias allowed)
				(pads allowed)
				(copperpour not_allowed)
				(footprints allowed)
			)
			(placement
				(enabled no)
				(sheetname "")
			)
			(fill
				(thermal_gap 0.5)
				(thermal_bridge_width 0.5)
				(island_removal_mode 0)
			)
			(polygon
				(pts
					(xy 329.207622 -242.171474) (xy 322.133722 -242.171474) (xy 322.133722 -235.237274) (xy 323.238622 -235.237274)
					(xy 323.238622 -239.352074) (xy 327.861422 -239.352074) (xy 327.861422 -235.237274) (xy 329.207622 -235.237274)
				)
			)
		)
		(zone
			(layer "F.Cu")
			(hatch none 0.5)
			(connect_pads
				(clearance 0)
			)
			(min_thickness 0.25)
			(keepout
				(tracks allowed)
				(vias not_allowed)
				(pads allowed)
				(copperpour not_allowed)
				(footprints allowed)
			)
			(placement
				(enabled no)
				(sheetname "")
			)
			(fill
				(thermal_gap 0.5)
				(thermal_bridge_width 0.5)
				(island_removal_mode 0)
			)
			(polygon
				(pts
					(xy 329.207622 -242.171474) (xy 322.133722 -242.171474) (xy 322.133722 -235.237274) (xy 323.238622 -235.237274)
					(xy 323.238622 -239.352074) (xy 327.861422 -239.352074) (xy 327.861422 -235.237274) (xy 329.207622 -235.237274)
				)
			)
		)
		(zone
			(layers "F.Cu" "B.Cu" "In1.Cu" "In2.Cu" "In3.Cu" "In4.Cu" "In5.Cu" "In6.Cu")
			(hatch none 0.5)
			(connect_pads
				(clearance 0)
			)
			(min_thickness 0.25)
			(keepout
				(tracks not_allowed)
				(vias allowed)
				(pads allowed)
				(copperpour not_allowed)
				(footprints allowed)
			)
			(placement
				(enabled no)
				(sheetname "")
			)
			(fill
				(thermal_gap 0.5)
				(thermal_bridge_width 0.5)
				(island_removal_mode 0)
			)
			(polygon
				(pts
					(arc
						(start 326.324722 -240.03508)
						(mid 324.775322 -240.03508)
						(end 326.324722 -240.03508)
					)
				)
			)
		)
		(zone
			(layers "F.Cu" "B.Cu" "In1.Cu" "In2.Cu" "In3.Cu" "In4.Cu" "In5.Cu" "In6.Cu")
			(hatch none 0.5)
			(connect_pads
				(clearance 0)
			)
			(min_thickness 0.25)
			(keepout
				(tracks not_allowed)
				(vias allowed)
				(pads allowed)
				(copperpour not_allowed)
				(footprints allowed)
			)
			(placement
				(enabled no)
				(sheetname "")
			)
			(fill
				(thermal_gap 0.5)
				(thermal_bridge_width 0.5)
				(island_removal_mode 0)
			)
			(polygon
				(pts
					(arc
						(start 326.527922 -277.785068)
						(mid 324.572122 -277.785068)
						(end 326.527922 -277.785068)
					)
				)
			)
		)
	)
	(footprint ""
		(layer "F.Cu")
		(at 467.5124 -5.3594 -90)
		(property "Reference" "R134"
			(at 0 0 270)
			(layer "F.SilkS")
			(hide yes)
			(effects
				(font
					(size 1.27 1.27)
				)
			)
		)
		(property "Value" "4K7R2F-GP"
			(at 0.064008 -3.993896 270)
			(unlocked yes)
			(layer "F.Fab")
			(hide yes)
			(effects
				(font
					(size 1.016 1.016)
					(thickness 0.1524)
				)
			)
		)
		(property "Device Type" "R402H16"
			(at 0.064008 -5.517896 270)
			(unlocked yes)
			(layer "F.Fab")
			(hide yes)
			(effects
				(font
					(size 1.016 1.016)
					(thickness 0.1524)
				)
			)
		)
		(duplicate_pad_numbers_are_jumpers no)
		(fp_line
			(start -0.508 -0.9398)
			(end -0.508 0.9398)
			(stroke
				(width 0.1524)
				(type default)
			)
			(layer "F.SilkS")
		)
		(fp_line
			(start 0.508 -0.9398)
			(end -0.508 -0.9398)
			(stroke
				(width 0.1524)
				(type default)
			)
			(layer "F.SilkS")
		)
		(fp_rect
			(start -0.508 0.9398)
			(end 0.508 -0.9398)
			(stroke
				(width 0)
				(type default)
			)
			(fill no)
			(layer "F.CrtYd")
		)
		(fp_rect
			(start -0.508 0.9398)
			(end 0.508 -0.9398)
			(stroke
				(width 0)
				(type default)
			)
			(fill no)
			(layer "F.Fab")
		)
		(pad "1" smd custom
			(at 0 -0.4445 270)
			(size 0.1397 0.1397)
			(layers "F.Cu" "F.Mask" "F.Paste")
			(net "P3V3_STBY_B")
			(options
				(clearance outline)
				(anchor circle)
			)
			(primitives
				(gr_poly
					(pts
						(arc
							(start -0.1778 -0.2794)
							(mid -0.249642 -0.249642)
							(end -0.2794 -0.1778)
						)
						(arc
							(start -0.2794 0.1778)
							(mid -0.249642 0.249642)
							(end -0.1778 0.2794)
						)
						(arc
							(start 0.1778 0.2794)
							(mid 0.249642 0.249642)
							(end 0.2794 0.1778)
						)
						(arc
							(start 0.2794 -0.1778)
							(mid 0.249642 -0.249642)
							(end 0.1778 -0.2794)
						)
					)
					(width 0)
					(fill yes)
				)
			)
		)
		(pad "2" smd custom
			(at 0 0.4445 270)
			(size 0.1397 0.1397)
			(layers "F.Cu" "F.Mask" "F.Paste")
			(net "TEMP2_A2")
			(options
				(clearance outline)
				(anchor circle)
			)
			(primitives
				(gr_poly
					(pts
						(arc
							(start -0.1778 -0.2794)
							(mid -0.249642 -0.249642)
							(end -0.2794 -0.1778)
						)
						(arc
							(start -0.2794 0.1778)
							(mid -0.249642 0.249642)
							(end -0.1778 0.2794)
						)
						(arc
							(start 0.1778 0.2794)
							(mid 0.249642 0.249642)
							(end 0.2794 0.1778)
						)
						(arc
							(start 0.2794 -0.1778)
							(mid 0.249642 -0.249642)
							(end 0.1778 -0.2794)
						)
					)
					(width 0)
					(fill yes)
				)
			)
		)
	)
	(footprint ""
		(layer "F.Cu")
		(at 238.633 -215.265)
		(property "Reference" "R88"
			(at 0 0 0)
			(layer "F.SilkS")
			(hide yes)
			(effects
				(font
					(size 1.27 1.27)
				)
			)
		)
		(property "Value" "0R2J-2-GP"
			(at 0.064008 -3.993896 0)
			(unlocked yes)
			(layer "F.Fab")
			(hide yes)
			(effects
				(font
					(size 1.016 1.016)
					(thickness 0.1524)
				)
			)
		)
		(property "Device Type" "R402H16"
			(at 0.064008 -5.517896 0)
			(unlocked yes)
			(layer "F.Fab")
			(hide yes)
			(effects
				(font
					(size 1.016 1.016)
					(thickness 0.1524)
				)
			)
		)
		(duplicate_pad_numbers_are_jumpers no)
		(fp_line
			(start -0.508 -0.9398)
			(end -0.508 0.9398)
			(stroke
				(width 0.1524)
				(type default)
			)
			(layer "F.SilkS")
		)
		(fp_line
			(start 0.508 -0.9398)
			(end -0.508 -0.9398)
			(stroke
				(width 0.1524)
				(type default)
			)
			(layer "F.SilkS")
		)
		(fp_rect
			(start -0.508 0.9398)
			(end 0.508 -0.9398)
			(stroke
				(width 0)
				(type default)
			)
			(fill no)
			(layer "F.CrtYd")
		)
		(fp_rect
			(start -0.508 0.9398)
			(end 0.508 -0.9398)
			(stroke
				(width 0)
				(type default)
			)
			(fill no)
			(layer "F.Fab")
		)
		(pad "1" smd custom
			(at 0 -0.4445)
			(size 0.1397 0.1397)
			(layers "F.Cu" "F.Mask" "F.Paste")
			(net "IO_EXP3_SDA")
			(options
				(clearance outline)
				(anchor circle)
			)
			(primitives
				(gr_poly
					(pts
						(arc
							(start -0.1778 -0.2794)
							(mid -0.249642 -0.249642)
							(end -0.2794 -0.1778)
						)
						(arc
							(start -0.2794 0.1778)
							(mid -0.249642 0.249642)
							(end -0.1778 0.2794)
						)
						(arc
							(start 0.1778 0.2794)
							(mid 0.249642 0.249642)
							(end 0.2794 0.1778)
						)
						(arc
							(start 0.2794 -0.1778)
							(mid 0.249642 -0.249642)
							(end 0.1778 -0.2794)
						)
					)
					(width 0)
					(fill yes)
				)
			)
		)
		(pad "2" smd custom
			(at 0 0.4445)
			(size 0.1397 0.1397)
			(layers "F.Cu" "F.Mask" "F.Paste")
			(net "I2C_DRIVE_B_PWR_SDA")
			(options
				(clearance outline)
				(anchor circle)
			)
			(primitives
				(gr_poly
					(pts
						(arc
							(start -0.1778 -0.2794)
							(mid -0.249642 -0.249642)
							(end -0.2794 -0.1778)
						)
						(arc
							(start -0.2794 0.1778)
							(mid -0.249642 0.249642)
							(end -0.1778 0.2794)
						)
						(arc
							(start 0.1778 0.2794)
							(mid 0.249642 0.249642)
							(end 0.2794 0.1778)
						)
						(arc
							(start 0.2794 -0.1778)
							(mid 0.249642 -0.249642)
							(end 0.1778 -0.2794)
						)
					)
					(width 0)
					(fill yes)
				)
			)
		)
	)
)
